(kicad_pcb
	(version 20260206)
	(generator "pcbnew")
	(generator_version "10.0")
	(general
		(thickness 1.6)
		(legacy_teardrops no)
	)
	(paper "A4")
	(title_block
		(title "01162023_DA0F0TEBIF0_F0T_Expander_BD_F_brd_V02_OCP.brd")
		(comment 1 "Grand Teton / footprints 788-796 of 9728")
	)
	(layers
		(0 "F.Cu" signal "TOP")
		(4 "In1.Cu" signal "GND")
		(6 "In2.Cu" signal "VCC")
		(8 "In3.Cu" signal "VCC1")
		(10 "In4.Cu" signal "GND1")
		(12 "In5.Cu" signal "IN1")
		(14 "In6.Cu" signal "GND2")
		(16 "In7.Cu" signal "IN2")
		(18 "In8.Cu" signal "GND3")
		(20 "In9.Cu" signal "IN3")
		(22 "In10.Cu" signal "GND4")
		(24 "In11.Cu" signal "IN4")
		(26 "In12.Cu" signal "GND5")
		(28 "In13.Cu" signal "IN5")
		(30 "In14.Cu" signal "GND6")
		(32 "In15.Cu" signal "IN6")
		(34 "In16.Cu" signal "GND7")
		(2 "B.Cu" signal "BOTTOM")
		(9 "F.Adhes" user "F.Adhesive")
		(11 "B.Adhes" user "B.Adhesive")
		(13 "F.Paste" user "Package Geometry/Pastemask Top")
		(15 "B.Paste" user "Package Geometry/Pastemask Bottom")
		(5 "F.SilkS" user "Ref Des/Silkscreen Top")
		(7 "B.SilkS" user "Ref Des/Silkscreen Bottom")
		(1 "F.Mask" user "Board Geometry/Soldermask Top")
		(3 "B.Mask" user "Board Geometry/Soldermask Bottom")
		(17 "Dwgs.User" user "User.Drawings")
		(19 "Cmts.User" user "User.Comments")
		(21 "Eco1.User" user "User.Eco1")
		(23 "Eco2.User" user "User.Eco2")
		(25 "Edge.Cuts" user "Board Geometry/Outline")
		(27 "Margin" user)
		(31 "F.CrtYd" user "Package Geometry/Place Bound Top")
		(29 "B.CrtYd" user "Package Geometry/Place Bound Bottom")
		(35 "F.Fab" user "Ref Des/Assembly Top")
		(33 "B.Fab" user "Ref Des/Assembly Bottom")
	)
	(footprint ""
		(layer "F.Cu")
		(at 354.212398 -205.150466 90)
		(property "Reference" "R5803"
			(at 0 0 90)
			(layer "F.SilkS")
			(hide yes)
			(effects
				(font
					(size 1.27 1.27)
				)
			)
		)
		(property "Value" ""
			(at 0 0 90)
			(layer "F.Fab")
			(effects
				(font
					(size 1.27 1.27)
				)
			)
		)
		(duplicate_pad_numbers_are_jumpers no)
		(fp_line
			(start 0.7874 -0.4064)
			(end 0.7874 0.4064)
			(stroke
				(width 0.1524)
				(type default)
			)
			(layer "F.SilkS")
		)
		(fp_line
			(start -0.7874 -0.4064)
			(end 0.7874 -0.4064)
			(stroke
				(width 0.1524)
				(type default)
			)
			(layer "F.SilkS")
		)
		(fp_line
			(start 0.7874 0.4064)
			(end -0.7874 0.4064)
			(stroke
				(width 0.1524)
				(type default)
			)
			(layer "F.SilkS")
		)
		(fp_line
			(start -0.7874 0.4064)
			(end -0.7874 -0.4064)
			(stroke
				(width 0.1524)
				(type default)
			)
			(layer "F.SilkS")
		)
		(fp_line
			(start -0.12065 -0.305054)
			(end -0.12065 -0.2794)
			(stroke
				(width 0.1)
				(type default)
			)
			(layer "F.Fab")
		)
		(fp_line
			(start -0.67945 -0.305054)
			(end -0.12065 -0.305054)
			(stroke
				(width 0.1)
				(type default)
			)
			(layer "F.Fab")
		)
		(fp_line
			(start 0.67945 -0.3048)
			(end 0.67945 0.3048)
			(stroke
				(width 0.1)
				(type default)
			)
			(layer "F.Fab")
		)
		(fp_line
			(start 0.12065 -0.3048)
			(end 0.67945 -0.3048)
			(stroke
				(width 0.1)
				(type default)
			)
			(layer "F.Fab")
		)
		(fp_line
			(start 0.12065 -0.2794)
			(end 0.12065 -0.3048)
			(stroke
				(width 0.1)
				(type default)
			)
			(layer "F.Fab")
		)
		(fp_line
			(start -0.12065 -0.2794)
			(end 0.12065 -0.2794)
			(stroke
				(width 0.1)
				(type default)
			)
			(layer "F.Fab")
		)
		(fp_line
			(start 0.120396 0.2794)
			(end -0.12065 0.2794)
			(stroke
				(width 0.1)
				(type default)
			)
			(layer "F.Fab")
		)
		(fp_line
			(start -0.12065 0.2794)
			(end -0.12065 0.3048)
			(stroke
				(width 0.1)
				(type default)
			)
			(layer "F.Fab")
		)
		(fp_line
			(start 0.67945 0.3048)
			(end 0.120396 0.3048)
			(stroke
				(width 0.1)
				(type default)
			)
			(layer "F.Fab")
		)
		(fp_line
			(start 0.120396 0.3048)
			(end 0.120396 0.2794)
			(stroke
				(width 0.1)
				(type default)
			)
			(layer "F.Fab")
		)
		(fp_line
			(start -0.12065 0.3048)
			(end -0.67945 0.3048)
			(stroke
				(width 0.1)
				(type default)
			)
			(layer "F.Fab")
		)
		(fp_line
			(start -0.67945 0.3048)
			(end -0.67945 -0.305054)
			(stroke
				(width 0.1)
				(type default)
			)
			(layer "F.Fab")
		)
		(pad "1" smd circle
			(at -0.40005 0 90)
			(size 0 0)
			(layers "F.Cu" "F.Mask" "F.Paste")
			(net "P3V3_FPGA_VCCIO2")
		)
		(pad "2" smd circle
			(at 0.40005 0 90)
			(size 0 0)
			(layers "F.Cu" "F.Mask" "F.Paste")
			(net "PU_FPGA_SN")
		)
	)
	(footprint ""
		(layer "F.Cu")
		(at 488.553252 -554.392338 180)
		(property "Reference" "SCREW_SSD6_2"
			(at -5.207 -1.402334 0)
			(unlocked yes)
			(layer "B.SilkS")
			(effects
				(font
					(size 0.7874 0.5842)
					(thickness 0.1524)
				)
				(justify mirror)
			)
		)
		(property "Value" ""
			(at 0 0 180)
			(layer "F.Fab")
			(effects
				(font
					(size 1.27 1.27)
				)
			)
		)
		(duplicate_pad_numbers_are_jumpers no)
		(pad "1" thru_hole circle
			(at 0 0 180)
			(size 0.4572 0.4572)
			(drill 0.2032)
			(layers "*.Cu" "*.Mask")
			(remove_unused_layers no)
			(net "Net_9131")
			(clearance 0.127)
			(thermal_gap 0.127)
			(padstack
				(mode front_inner_back)
				(layer "Inner"
					(shape circle)
					(size 0.4572 0.4572)
					(clearance 0.127)
				)
				(layer "B.Cu"
					(shape circle)
					(size 0.508 0.508)
					(clearance 0.1016)
				)
			)
		)
	)
	(footprint ""
		(layer "F.Cu")
		(at 428.319438 -118.670324 180)
		(property "Reference" "C665"
			(at 0 0 180)
			(layer "F.SilkS")
			(hide yes)
			(effects
				(font
					(size 1.27 1.27)
				)
			)
		)
		(property "Value" ""
			(at 0 0 180)
			(layer "F.Fab")
			(effects
				(font
					(size 1.27 1.27)
				)
			)
		)
		(duplicate_pad_numbers_are_jumpers no)
		(fp_line
			(start 0.299974 0.150114)
			(end -0.299974 0.150114)
			(stroke
				(width 0.1)
				(type default)
			)
			(layer "F.Fab")
		)
		(fp_line
			(start 0.299974 -0.150114)
			(end 0.299974 0.150114)
			(stroke
				(width 0.1)
				(type default)
			)
			(layer "F.Fab")
		)
		(fp_line
			(start -0.299974 0.150114)
			(end -0.299974 -0.150114)
			(stroke
				(width 0.1)
				(type default)
			)
			(layer "F.Fab")
		)
		(fp_line
			(start -0.299974 -0.150114)
			(end 0.299974 -0.150114)
			(stroke
				(width 0.1)
				(type default)
			)
			(layer "F.Fab")
		)
		(pad "1" smd rect
			(at -0.2667 0 180)
			(size 0.3048 0.381)
			(layers "F.Cu" "F.Mask" "F.Paste")
			(net "P5E_PEX3_STN0_TX_DN<0>")
		)
		(pad "2" smd rect
			(at 0.2667 0 180)
			(size 0.3048 0.381)
			(layers "F.Cu" "F.Mask" "F.Paste")
			(net "P5E_PEX3_STN0_TX_C_DN<0>")
		)
	)
	(footprint ""
		(layer "F.Cu")
		(at 210.59394 -113.870486)
		(property "Reference" "PR7014"
			(at 0 0 0)
			(layer "F.SilkS")
			(hide yes)
			(effects
				(font
					(size 1.27 1.27)
				)
			)
		)
		(property "Value" ""
			(at 0 0 0)
			(layer "F.Fab")
			(effects
				(font
					(size 1.27 1.27)
				)
			)
		)
		(duplicate_pad_numbers_are_jumpers no)
		(fp_line
			(start -0.7874 -0.4064)
			(end 0.7874 -0.4064)
			(stroke
				(width 0.1524)
				(type default)
			)
			(layer "F.SilkS")
		)
		(fp_line
			(start -0.7874 0.4064)
			(end -0.7874 -0.4064)
			(stroke
				(width 0.1524)
				(type default)
			)
			(layer "F.SilkS")
		)
		(fp_line
			(start 0.7874 -0.4064)
			(end 0.7874 0.4064)
			(stroke
				(width 0.1524)
				(type default)
			)
			(layer "F.SilkS")
		)
		(fp_line
			(start 0.7874 0.4064)
			(end -0.7874 0.4064)
			(stroke
				(width 0.1524)
				(type default)
			)
			(layer "F.SilkS")
		)
		(fp_line
			(start -0.67945 -0.305054)
			(end -0.12065 -0.305054)
			(stroke
				(width 0.1)
				(type default)
			)
			(layer "F.Fab")
		)
		(fp_line
			(start -0.67945 0.3048)
			(end -0.67945 -0.305054)
			(stroke
				(width 0.1)
				(type default)
			)
			(layer "F.Fab")
		)
		(fp_line
			(start -0.12065 -0.305054)
			(end -0.12065 -0.2794)
			(stroke
				(width 0.1)
				(type default)
			)
			(layer "F.Fab")
		)
		(fp_line
			(start -0.12065 -0.2794)
			(end 0.12065 -0.2794)
			(stroke
				(width 0.1)
				(type default)
			)
			(layer "F.Fab")
		)
		(fp_line
			(start -0.12065 0.2794)
			(end -0.12065 0.3048)
			(stroke
				(width 0.1)
				(type default)
			)
			(layer "F.Fab")
		)
		(fp_line
			(start -0.12065 0.3048)
			(end -0.67945 0.3048)
			(stroke
				(width 0.1)
				(type default)
			)
			(layer "F.Fab")
		)
		(fp_line
			(start 0.120396 0.2794)
			(end -0.12065 0.2794)
			(stroke
				(width 0.1)
				(type default)
			)
			(layer "F.Fab")
		)
		(fp_line
			(start 0.120396 0.3048)
			(end 0.120396 0.2794)
			(stroke
				(width 0.1)
				(type default)
			)
			(layer "F.Fab")
		)
		(fp_line
			(start 0.12065 -0.3048)
			(end 0.67945 -0.3048)
			(stroke
				(width 0.1)
				(type default)
			)
			(layer "F.Fab")
		)
		(fp_line
			(start 0.12065 -0.2794)
			(end 0.12065 -0.3048)
			(stroke
				(width 0.1)
				(type default)
			)
			(layer "F.Fab")
		)
		(fp_line
			(start 0.67945 -0.3048)
			(end 0.67945 0.3048)
			(stroke
				(width 0.1)
				(type default)
			)
			(layer "F.Fab")
		)
		(fp_line
			(start 0.67945 0.3048)
			(end 0.120396 0.3048)
			(stroke
				(width 0.1)
				(type default)
			)
			(layer "F.Fab")
		)
		(pad "1" smd circle
			(at -0.40005 0)
			(size 0 0)
			(layers "F.Cu" "F.Mask" "F.Paste")
			(net "P3V3_NIC3_CO_ILIMIT")
		)
		(pad "2" smd circle
			(at 0.40005 0)
			(size 0 0)
			(layers "F.Cu" "F.Mask" "F.Paste")
			(net "GND")
		)
	)
	(footprint ""
		(layer "F.Cu")
		(at 142.125192 -14.735302 180)
		(property "Reference" "C2720"
			(at 0 0 180)
			(layer "F.SilkS")
			(hide yes)
			(effects
				(font
					(size 1.27 1.27)
				)
			)
		)
		(property "Value" ""
			(at 0 0 180)
			(layer "F.Fab")
			(effects
				(font
					(size 1.27 1.27)
				)
			)
		)
		(duplicate_pad_numbers_are_jumpers no)
		(fp_line
			(start 0.7874 0.4064)
			(end -0.7874 0.4064)
			(stroke
				(width 0.1524)
				(type default)
			)
			(layer "F.SilkS")
		)
		(fp_line
			(start 0.7874 -0.4064)
			(end 0.7874 0.4064)
			(stroke
				(width 0.1524)
				(type default)
			)
			(layer "F.SilkS")
		)
		(fp_line
			(start -0.7874 0.4064)
			(end -0.7874 -0.4064)
			(stroke
				(width 0.1524)
				(type default)
			)
			(layer "F.SilkS")
		)
		(fp_line
			(start -0.7874 -0.4064)
			(end 0.7874 -0.4064)
			(stroke
				(width 0.1524)
				(type default)
			)
			(layer "F.SilkS")
		)
		(fp_line
			(start 0.67945 0.3048)
			(end 0.120396 0.3048)
			(stroke
				(width 0.1)
				(type default)
			)
			(layer "F.Fab")
		)
		(fp_line
			(start 0.67945 -0.3048)
			(end 0.67945 0.3048)
			(stroke
				(width 0.1)
				(type default)
			)
			(layer "F.Fab")
		)
		(fp_line
			(start 0.12065 -0.2794)
			(end 0.12065 -0.3048)
			(stroke
				(width 0.1)
				(type default)
			)
			(layer "F.Fab")
		)
		(fp_line
			(start 0.12065 -0.3048)
			(end 0.67945 -0.3048)
			(stroke
				(width 0.1)
				(type default)
			)
			(layer "F.Fab")
		)
		(fp_line
			(start 0.120396 0.3048)
			(end 0.120396 0.2794)
			(stroke
				(width 0.1)
				(type default)
			)
			(layer "F.Fab")
		)
		(fp_line
			(start 0.120396 0.2794)
			(end -0.12065 0.2794)
			(stroke
				(width 0.1)
				(type default)
			)
			(layer "F.Fab")
		)
		(fp_line
			(start -0.12065 0.3048)
			(end -0.67945 0.3048)
			(stroke
				(width 0.1)
				(type default)
			)
			(layer "F.Fab")
		)
		(fp_line
			(start -0.12065 0.2794)
			(end -0.12065 0.3048)
			(stroke
				(width 0.1)
				(type default)
			)
			(layer "F.Fab")
		)
		(fp_line
			(start -0.12065 -0.2794)
			(end 0.12065 -0.2794)
			(stroke
				(width 0.1)
				(type default)
			)
			(layer "F.Fab")
		)
		(fp_line
			(start -0.12065 -0.305054)
			(end -0.12065 -0.2794)
			(stroke
				(width 0.1)
				(type default)
			)
			(layer "F.Fab")
		)
		(fp_line
			(start -0.67945 0.3048)
			(end -0.67945 -0.305054)
			(stroke
				(width 0.1)
				(type default)
			)
			(layer "F.Fab")
		)
		(fp_line
			(start -0.67945 -0.305054)
			(end -0.12065 -0.305054)
			(stroke
				(width 0.1)
				(type default)
			)
			(layer "F.Fab")
		)
		(pad "1" smd circle
			(at -0.40005 0 180)
			(size 0 0)
			(layers "F.Cu" "F.Mask" "F.Paste")
			(net "GND")
		)
		(pad "2" smd circle
			(at 0.40005 0 180)
			(size 0 0)
			(layers "F.Cu" "F.Mask" "F.Paste")
			(net "P3V3_SSD4")
		)
	)
	(footprint ""
		(layer "F.Cu")
		(at 491.797848 -552.071032 180)
		(property "Reference" "J31_OTH"
			(at -3.2385 -1.402334 0)
			(unlocked yes)
			(layer "B.SilkS")
			(effects
				(font
					(size 0.7874 0.5842)
					(thickness 0.1524)
				)
				(justify mirror)
			)
		)
		(property "Value" ""
			(at 0 0 180)
			(layer "F.Fab")
			(effects
				(font
					(size 1.27 1.27)
				)
			)
		)
		(duplicate_pad_numbers_are_jumpers no)
		(pad "1" thru_hole circle
			(at 0 0 180)
			(size 0.4572 0.4572)
			(drill 0.2032)
			(layers "*.Cu" "*.Mask")
			(remove_unused_layers no)
			(net "Net_9105")
			(clearance 0.127)
			(thermal_gap 0.127)
			(padstack
				(mode front_inner_back)
				(layer "Inner"
					(shape circle)
					(size 0.4572 0.4572)
					(clearance 0.127)
				)
				(layer "B.Cu"
					(shape circle)
					(size 0.508 0.508)
					(clearance 0.1016)
				)
			)
		)
	)
	(footprint ""
		(layer "F.Cu")
		(at 119.972328 -32.848042 90)
		(property "Reference" "PC920"
			(at 0 0 90)
			(layer "F.SilkS")
			(hide yes)
			(effects
				(font
					(size 1.27 1.27)
				)
			)
		)
		(property "Value" ""
			(at 0 0 90)
			(layer "F.Fab")
			(effects
				(font
					(size 1.27 1.27)
				)
			)
		)
		(duplicate_pad_numbers_are_jumpers no)
		(fp_line
			(start 0.7874 -0.4064)
			(end 0.7874 0.4064)
			(stroke
				(width 0.1524)
				(type default)
			)
			(layer "F.SilkS")
		)
		(fp_line
			(start -0.7874 -0.4064)
			(end 0.7874 -0.4064)
			(stroke
				(width 0.1524)
				(type default)
			)
			(layer "F.SilkS")
		)
		(fp_line
			(start 0.7874 0.4064)
			(end -0.7874 0.4064)
			(stroke
				(width 0.1524)
				(type default)
			)
			(layer "F.SilkS")
		)
		(fp_line
			(start -0.7874 0.4064)
			(end -0.7874 -0.4064)
			(stroke
				(width 0.1524)
				(type default)
			)
			(layer "F.SilkS")
		)
		(fp_line
			(start -0.12065 -0.305054)
			(end -0.12065 -0.2794)
			(stroke
				(width 0.1)
				(type default)
			)
			(layer "F.Fab")
		)
		(fp_line
			(start -0.67945 -0.305054)
			(end -0.12065 -0.305054)
			(stroke
				(width 0.1)
				(type default)
			)
			(layer "F.Fab")
		)
		(fp_line
			(start 0.67945 -0.3048)
			(end 0.67945 0.3048)
			(stroke
				(width 0.1)
				(type default)
			)
			(layer "F.Fab")
		)
		(fp_line
			(start 0.12065 -0.3048)
			(end 0.67945 -0.3048)
			(stroke
				(width 0.1)
				(type default)
			)
			(layer "F.Fab")
		)
		(fp_line
			(start 0.12065 -0.2794)
			(end 0.12065 -0.3048)
			(stroke
				(width 0.1)
				(type default)
			)
			(layer "F.Fab")
		)
		(fp_line
			(start -0.12065 -0.2794)
			(end 0.12065 -0.2794)
			(stroke
				(width 0.1)
				(type default)
			)
			(layer "F.Fab")
		)
		(fp_line
			(start 0.120396 0.2794)
			(end -0.12065 0.2794)
			(stroke
				(width 0.1)
				(type default)
			)
			(layer "F.Fab")
		)
		(fp_line
			(start -0.12065 0.2794)
			(end -0.12065 0.3048)
			(stroke
				(width 0.1)
				(type default)
			)
			(layer "F.Fab")
		)
		(fp_line
			(start 0.67945 0.3048)
			(end 0.120396 0.3048)
			(stroke
				(width 0.1)
				(type default)
			)
			(layer "F.Fab")
		)
		(fp_line
			(start 0.120396 0.3048)
			(end 0.120396 0.2794)
			(stroke
				(width 0.1)
				(type default)
			)
			(layer "F.Fab")
		)
		(fp_line
			(start -0.12065 0.3048)
			(end -0.67945 0.3048)
			(stroke
				(width 0.1)
				(type default)
			)
			(layer "F.Fab")
		)
		(fp_line
			(start -0.67945 0.3048)
			(end -0.67945 -0.305054)
			(stroke
				(width 0.1)
				(type default)
			)
			(layer "F.Fab")
		)
		(pad "1" smd circle
			(at -0.40005 0 90)
			(size 0 0)
			(layers "F.Cu" "F.Mask" "F.Paste")
			(net "P3V3_SSD4_CO_GATE")
		)
		(pad "2" smd circle
			(at 0.40005 0 90)
			(size 0 0)
			(layers "F.Cu" "F.Mask" "F.Paste")
			(net "GND")
		)
	)
	(footprint ""
		(layer "F.Cu")
		(at 430.961546 -124.076714 180)
		(property "Reference" "C659"
			(at 0 0 180)
			(layer "F.SilkS")
			(hide yes)
			(effects
				(font
					(size 1.27 1.27)
				)
			)
		)
		(property "Value" ""
			(at 0 0 180)
			(layer "F.Fab")
			(effects
				(font
					(size 1.27 1.27)
				)
			)
		)
		(duplicate_pad_numbers_are_jumpers no)
		(fp_line
			(start 0.299974 0.150114)
			(end -0.299974 0.150114)
			(stroke
				(width 0.1)
				(type default)
			)
			(layer "F.Fab")
		)
		(fp_line
			(start 0.299974 -0.150114)
			(end 0.299974 0.150114)
			(stroke
				(width 0.1)
				(type default)
			)
			(layer "F.Fab")
		)
		(fp_line
			(start -0.299974 0.150114)
			(end -0.299974 -0.150114)
			(stroke
				(width 0.1)
				(type default)
			)
			(layer "F.Fab")
		)
		(fp_line
			(start -0.299974 -0.150114)
			(end 0.299974 -0.150114)
			(stroke
				(width 0.1)
				(type default)
			)
			(layer "F.Fab")
		)
		(pad "1" smd rect
			(at -0.2667 0 180)
			(size 0.3048 0.381)
			(layers "F.Cu" "F.Mask" "F.Paste")
			(net "P5E_PEX3_STN0_TX_DN<3>")
		)
		(pad "2" smd rect
			(at 0.2667 0 180)
			(size 0.3048 0.381)
			(layers "F.Cu" "F.Mask" "F.Paste")
			(net "P5E_PEX3_STN0_TX_C_DN<3>")
		)
	)
	(footprint ""
		(layer "F.Cu")
		(at 92.538804 -122.798332 90)
		(property "Reference" "PC464"
			(at 0 0 90)
			(layer "F.SilkS")
			(hide yes)
			(effects
				(font
					(size 1.27 1.27)
				)
			)
		)
		(property "Value" ""
			(at 0 0 90)
			(layer "F.Fab")
			(effects
				(font
					(size 1.27 1.27)
				)
			)
		)
		(duplicate_pad_numbers_are_jumpers no)
		(fp_line
			(start 0.7874 -0.4064)
			(end 0.7874 0.4064)
			(stroke
				(width 0.1524)
				(type default)
			)
			(layer "F.SilkS")
		)
		(fp_line
			(start -0.7874 -0.4064)
			(end 0.7874 -0.4064)
			(stroke
				(width 0.1524)
				(type default)
			)
			(layer "F.SilkS")
		)
		(fp_line
			(start 0.7874 0.4064)
			(end -0.7874 0.4064)
			(stroke
				(width 0.1524)
				(type default)
			)
			(layer "F.SilkS")
		)
		(fp_line
			(start -0.7874 0.4064)
			(end -0.7874 -0.4064)
			(stroke
				(width 0.1524)
				(type default)
			)
			(layer "F.SilkS")
		)
		(fp_line
			(start -0.12065 -0.305054)
			(end -0.12065 -0.2794)
			(stroke
				(width 0.1)
				(type default)
			)
			(layer "F.Fab")
		)
		(fp_line
			(start -0.67945 -0.305054)
			(end -0.12065 -0.305054)
			(stroke
				(width 0.1)
				(type default)
			)
			(layer "F.Fab")
		)
		(fp_line
			(start 0.67945 -0.3048)
			(end 0.67945 0.3048)
			(stroke
				(width 0.1)
				(type default)
			)
			(layer "F.Fab")
		)
		(fp_line
			(start 0.12065 -0.3048)
			(end 0.67945 -0.3048)
			(stroke
				(width 0.1)
				(type default)
			)
			(layer "F.Fab")
		)
		(fp_line
			(start 0.12065 -0.2794)
			(end 0.12065 -0.3048)
			(stroke
				(width 0.1)
				(type default)
			)
			(layer "F.Fab")
		)
		(fp_line
			(start -0.12065 -0.2794)
			(end 0.12065 -0.2794)
			(stroke
				(width 0.1)
				(type default)
			)
			(layer "F.Fab")
		)
		(fp_line
			(start 0.120396 0.2794)
			(end -0.12065 0.2794)
			(stroke
				(width 0.1)
				(type default)
			)
			(layer "F.Fab")
		)
		(fp_line
			(start -0.12065 0.2794)
			(end -0.12065 0.3048)
			(stroke
				(width 0.1)
				(type default)
			)
			(layer "F.Fab")
		)
		(fp_line
			(start 0.67945 0.3048)
			(end 0.120396 0.3048)
			(stroke
				(width 0.1)
				(type default)
			)
			(layer "F.Fab")
		)
		(fp_line
			(start 0.120396 0.3048)
			(end 0.120396 0.2794)
			(stroke
				(width 0.1)
				(type default)
			)
			(layer "F.Fab")
		)
		(fp_line
			(start -0.12065 0.3048)
			(end -0.67945 0.3048)
			(stroke
				(width 0.1)
				(type default)
			)
			(layer "F.Fab")
		)
		(fp_line
			(start -0.67945 0.3048)
			(end -0.67945 -0.305054)
			(stroke
				(width 0.1)
				(type default)
			)
			(layer "F.Fab")
		)
		(pad "1" smd circle
			(at -0.40005 0 90)
			(size 0 0)
			(layers "F.Cu" "F.Mask" "F.Paste")
			(net "P3V3_NIC1")
		)
		(pad "2" smd circle
			(at 0.40005 0 90)
			(size 0 0)
			(layers "F.Cu" "F.Mask" "F.Paste")
			(net "GND")
		)
	)
)
